FILE_TYPE = MACRO_DRAWING;
SET COLOR_WIRE YELLOW;
SET COLOR_PROP MONO;
SET COLOR_DOT WHITE;
SET COLOR_ARC YELLOW;
SET COLOR_BODY GREEN;
SET COLOR_NOTE MONO;
SET PROP_DISPLAY VALUE;
SET PAGE_NUMBER P260;
FORCEADD INTEL_CORP_BPAGE..1
(-1500 1925);
FORCEPROP 1 LAST CDS_CON_LAST_MODIFIED Fri Jun 16 17:49:37 2017
J 0
(-2925 2250);
PAINT ORANGE (-2925 2250);
DISPLAY INVISIBLE (-2925 2250);
FORCEPROP 1 LAST CUSTOM_TXT_CDS <CURRENT_DESIGN_SHEET> OF <TOTAL_DESIGN_SHEETS>
J 0
(-2000 1950);
PAINT ORANGE (-2000 1950);
FORCEPROP 2 LAST CUSTOM_TXT_CDS <XR_PAGE_TITLE>
J 0
(-9390 7175);
DISPLAY 0.638298 (-9390 7175);
PAINT PINK (-9390 7175);
DISPLAY INVISIBLE (-9390 7175);
FORCEPROP 2 LAST CUSTOM_TXT_CDS <CON_LAST_MODIFIED>
J 0
(-5500 2025);
PAINT ORANGE (-5500 2025);
FORCEPROP 1 LAST SCH_TITLE SPI BLOCK DIAGRAM 2 OF 2
J 0
(-9450 1975);
DISPLAY 2.468085 (-9450 1975);
PAINT ORANGE (-9450 1975);
FORCEPROP 2 LAST PAGE_BORDER TRUE
J 0
(-9390 7175);
DISPLAY 0.638298 (-9390 7175);
PAINT PINK (-9390 7175);
DISPLAY INVISIBLE (-9390 7175);
FORCEPROP 2 LAST CDS_LIB mstr_symbols
J 0
(-1500 1925);
PAINT MONO (-1500 1925);
DISPLAY INVISIBLE (-1500 1925);
FORCEPROP 1 LAST COMMENT_BODY TRUE
J 0
(-1488 1937);
DISPLAY 0.468085 (-1488 1937);
PAINT GREEN (-1488 1937);
DISPLAY INVISIBLE (-1488 1937);
FORCEPROP 2 LAST CDS_XR_PAGE_TITLE CR-263 : @BASEBOARD_FAB2_LIB.BASEBOARD_FAB2(SCH_1):PAGE263
J 0
(-9390 7175);
DISPLAY 0.638298 (-9390 7175);
PAINT PINK (-9390 7175);
DISPLAY INVISIBLE (-9390 7175);
FORCENOTE
$CDS_IMAGE|SPI Block diagram_2_0406_J.jpg|6666|5000
(-5500 4400) 0;
DISPLAY LEFT (-5500 4400);
QUIT
